# S9S_MB_2U (Grand Teton) — schematic netlist excerpt (pin names and nets, part order shuffled) for the footprints in the layout excerpt that follows; sources: Cadence DE-HDL packaged netlist, KiCad conversion of 03242023_DA0F0TMBIJ0_F0T_Motherboard_J_brd_V01_OCP.brd

R2359  Q_RES  10K 1% CHIP  pkg 0402LF  page 263 : A = P3V3_AUX ; B = PWRGD_P1V8_PCH_AUX_R
C546  Q_CAP  1UF 25V 10% X6S  pkg C0402  page 132 : A = P3V3_AUX ; B = GND

(kicad_pcb
	(version 20260206)
	(generator "pcbnew")
	(generator_version "10.0")
	(general
		(thickness 1.6)
		(legacy_teardrops no)
	)
	(paper "A4")
	(title_block
		(title "03242023_DA0F0TMBIJ0_F0T_Motherboard_J_brd_V01_OCP.brd")
		(comment 1 "Grand Teton / footprints 889-890 of 6105")
	)
	(layers
		(0 "F.Cu" signal "TOP")
		(4 "In1.Cu" signal "GND")
		(6 "In2.Cu" signal "IN1")
		(8 "In3.Cu" signal "GND1")
		(10 "In4.Cu" signal "IN2")
		(12 "In5.Cu" signal "GND2")
		(14 "In6.Cu" signal "IN3")
		(16 "In7.Cu" signal "GND3")
		(18 "In8.Cu" signal "VCC")
		(20 "In9.Cu" signal "VCC1")
		(22 "In10.Cu" signal "GND4")
		(24 "In11.Cu" signal "IN4")
		(26 "In12.Cu" signal "GND5")
		(28 "In13.Cu" signal "IN5")
		(30 "In14.Cu" signal "GND6")
		(32 "In15.Cu" signal "IN6")
		(34 "In16.Cu" signal "GND7")
		(2 "B.Cu" signal "BOTTOM")
		(9 "F.Adhes" user "F.Adhesive")
		(11 "B.Adhes" user "B.Adhesive")
		(13 "F.Paste" user "Package Geometry/Pastemask Top")
		(15 "B.Paste" user "Package Geometry/Pastemask Bottom")
		(5 "F.SilkS" user "Ref Des/Silkscreen Top")
		(7 "B.SilkS" user "Ref Des/Silkscreen Bottom")
		(1 "F.Mask" user "Board Geometry/Soldermask Top")
		(3 "B.Mask" user "Board Geometry/Soldermask Bottom")
		(17 "Dwgs.User" user "User.Drawings")
		(19 "Cmts.User" user "User.Comments")
		(21 "Eco1.User" user "User.Eco1")
		(23 "Eco2.User" user "User.Eco2")
		(25 "Edge.Cuts" user "Board Geometry/Outline")
		(27 "Margin" user)
		(31 "F.CrtYd" user "Package Geometry/Place Bound Top")
		(29 "B.CrtYd" user "Package Geometry/Place Bound Bottom")
		(35 "F.Fab" user "Ref Des/Assembly Top")
		(33 "B.Fab" user "Ref Des/Assembly Bottom")
	)
	(footprint ""
		(layer "F.Cu")
		(at 385.637532 -73.394824 180)
		(property "Reference" "R2359"
			(at 0 0 180)
			(layer "F.SilkS")
			(hide yes)
			(effects
				(font
					(size 1.27 1.27)
				)
			)
		)
		(property "Value" ""
			(at 0 0 180)
			(layer "F.Fab")
			(effects
				(font
					(size 1.27 1.27)
				)
			)
		)
		(duplicate_pad_numbers_are_jumpers no)
		(fp_line
			(start 0.7874 0.4064)
			(end -0.7874 0.4064)
			(stroke
				(width 0.1524)
				(type default)
			)
			(layer "F.SilkS")
		)
		(fp_line
			(start 0.7874 -0.4064)
			(end 0.7874 0.4064)
			(stroke
				(width 0.1524)
				(type default)
			)
			(layer "F.SilkS")
		)
		(fp_line
			(start -0.7874 0.4064)
			(end -0.7874 -0.4064)
			(stroke
				(width 0.1524)
				(type default)
			)
			(layer "F.SilkS")
		)
		(fp_line
			(start -0.7874 -0.4064)
			(end 0.7874 -0.4064)
			(stroke
				(width 0.1524)
				(type default)
			)
			(layer "F.SilkS")
		)
		(fp_line
			(start 0.67945 0.3048)
			(end 0.120396 0.3048)
			(stroke
				(width 0.1)
				(type default)
			)
			(layer "F.Fab")
		)
		(fp_line
			(start 0.67945 -0.3048)
			(end 0.67945 0.3048)
			(stroke
				(width 0.1)
				(type default)
			)
			(layer "F.Fab")
		)
		(fp_line
			(start 0.12065 -0.2794)
			(end 0.12065 -0.3048)
			(stroke
				(width 0.1)
				(type default)
			)
			(layer "F.Fab")
		)
		(fp_line
			(start 0.12065 -0.3048)
			(end 0.67945 -0.3048)
			(stroke
				(width 0.1)
				(type default)
			)
			(layer "F.Fab")
		)
		(fp_line
			(start 0.120396 0.3048)
			(end 0.120396 0.2794)
			(stroke
				(width 0.1)
				(type default)
			)
			(layer "F.Fab")
		)
		(fp_line
			(start 0.120396 0.2794)
			(end -0.12065 0.2794)
			(stroke
				(width 0.1)
				(type default)
			)
			(layer "F.Fab")
		)
		(fp_line
			(start -0.12065 0.3048)
			(end -0.67945 0.3048)
			(stroke
				(width 0.1)
				(type default)
			)
			(layer "F.Fab")
		)
		(fp_line
			(start -0.12065 0.2794)
			(end -0.12065 0.3048)
			(stroke
				(width 0.1)
				(type default)
			)
			(layer "F.Fab")
		)
		(fp_line
			(start -0.12065 -0.2794)
			(end 0.12065 -0.2794)
			(stroke
				(width 0.1)
				(type default)
			)
			(layer "F.Fab")
		)
		(fp_line
			(start -0.12065 -0.305054)
			(end -0.12065 -0.2794)
			(stroke
				(width 0.1)
				(type default)
			)
			(layer "F.Fab")
		)
		(fp_line
			(start -0.67945 0.3048)
			(end -0.67945 -0.305054)
			(stroke
				(width 0.1)
				(type default)
			)
			(layer "F.Fab")
		)
		(fp_line
			(start -0.67945 -0.305054)
			(end -0.12065 -0.305054)
			(stroke
				(width 0.1)
				(type default)
			)
			(layer "F.Fab")
		)
		(pad "1" smd circle
			(at -0.40005 0 180)
			(size 0 0)
			(layers "F.Cu" "F.Mask" "F.Paste")
			(net "P3V3_AUX")
		)
		(pad "2" smd circle
			(at 0.40005 0 180)
			(size 0 0)
			(layers "F.Cu" "F.Mask" "F.Paste")
			(net "PWRGD_P1V8_PCH_AUX_R")
		)
	)
	(footprint ""
		(layer "F.Cu")
		(at 372.13159 -68.930012)
		(property "Reference" "C546"
			(at 0 0 0)
			(layer "F.SilkS")
			(hide yes)
			(effects
				(font
					(size 1.27 1.27)
				)
			)
		)
		(property "Value" ""
			(at 0 0 0)
			(layer "F.Fab")
			(effects
				(font
					(size 1.27 1.27)
				)
			)
		)
		(duplicate_pad_numbers_are_jumpers no)
		(fp_line
			(start -0.7874 -0.4064)
			(end 0.7874 -0.4064)
			(stroke
				(width 0.1524)
				(type default)
			)
			(layer "F.SilkS")
		)
		(fp_line
			(start -0.7874 0.4064)
			(end -0.7874 -0.4064)
			(stroke
				(width 0.1524)
				(type default)
			)
			(layer "F.SilkS")
		)
		(fp_line
			(start 0.7874 -0.4064)
			(end 0.7874 0.4064)
			(stroke
				(width 0.1524)
				(type default)
			)
			(layer "F.SilkS")
		)
		(fp_line
			(start 0.7874 0.4064)
			(end -0.7874 0.4064)
			(stroke
				(width 0.1524)
				(type default)
			)
			(layer "F.SilkS")
		)
		(fp_line
			(start -0.67945 -0.305054)
			(end -0.12065 -0.305054)
			(stroke
				(width 0.1)
				(type default)
			)
			(layer "F.Fab")
		)
		(fp_line
			(start -0.67945 0.3048)
			(end -0.67945 -0.305054)
			(stroke
				(width 0.1)
				(type default)
			)
			(layer "F.Fab")
		)
		(fp_line
			(start -0.12065 -0.305054)
			(end -0.12065 -0.2794)
			(stroke
				(width 0.1)
				(type default)
			)
			(layer "F.Fab")
		)
		(fp_line
			(start -0.12065 -0.2794)
			(end 0.12065 -0.2794)
			(stroke
				(width 0.1)
				(type default)
			)
			(layer "F.Fab")
		)
		(fp_line
			(start -0.12065 0.2794)
			(end -0.12065 0.3048)
			(stroke
				(width 0.1)
				(type default)
			)
			(layer "F.Fab")
		)
		(fp_line
			(start -0.12065 0.3048)
			(end -0.67945 0.3048)
			(stroke
				(width 0.1)
				(type default)
			)
			(layer "F.Fab")
		)
		(fp_line
			(start 0.120396 0.2794)
			(end -0.12065 0.2794)
			(stroke
				(width 0.1)
				(type default)
			)
			(layer "F.Fab")
		)
		(fp_line
			(start 0.120396 0.3048)
			(end 0.120396 0.2794)
			(stroke
				(width 0.1)
				(type default)
			)
			(layer "F.Fab")
		)
		(fp_line
			(start 0.12065 -0.3048)
			(end 0.67945 -0.3048)
			(stroke
				(width 0.1)
				(type default)
			)
			(layer "F.Fab")
		)
		(fp_line
			(start 0.12065 -0.2794)
			(end 0.12065 -0.3048)
			(stroke
				(width 0.1)
				(type default)
			)
			(layer "F.Fab")
		)
		(fp_line
			(start 0.67945 -0.3048)
			(end 0.67945 0.3048)
			(stroke
				(width 0.1)
				(type default)
			)
			(layer "F.Fab")
		)
		(fp_line
			(start 0.67945 0.3048)
			(end 0.120396 0.3048)
			(stroke
				(width 0.1)
				(type default)
			)
			(layer "F.Fab")
		)
		(pad "1" smd circle
			(at -0.40005 0)
			(size 0 0)
			(layers "F.Cu" "F.Mask" "F.Paste")
			(net "P3V3_AUX")
		)
		(pad "2" smd circle
			(at 0.40005 0)
			(size 0 0)
			(layers "F.Cu" "F.Mask" "F.Paste")
			(net "GND")
		)
	)
)
